(kicad_pcb
	(version 20260206)
	(generator "pcbnew")
	(generator_version "10.0")
	(general
		(thickness 1.6)
		(legacy_teardrops no)
	)
	(paper "A4")
	(title_block
		(title "baseboard — 13948-1b.1110WZS1818.brd")
		(comment 1 "Honey Badger (Wiwynn) / footprints 1155-1158 of 2523")
	)
	(layers
		(0 "F.Cu" signal "TOP")
		(4 "In1.Cu" signal "L2GND")
		(6 "In2.Cu" signal "L3")
		(8 "In3.Cu" signal "L4VCC")
		(10 "In4.Cu" signal "L5VCC")
		(12 "In5.Cu" signal "L6")
		(14 "In6.Cu" signal "L7GND")
		(2 "B.Cu" signal "BOTTOM")
		(9 "F.Adhes" user "F.Adhesive")
		(11 "B.Adhes" user "B.Adhesive")
		(13 "F.Paste" user "Package Geometry/Pastemask Top")
		(15 "B.Paste" user "Package Geometry/Pastemask Bottom")
		(5 "F.SilkS" user "Ref Des/Silkscreen Top")
		(7 "B.SilkS" user "Ref Des/Silkscreen Bottom")
		(1 "F.Mask" user "Board Geometry/Soldermask Top")
		(3 "B.Mask" user "Board Geometry/Soldermask Bottom")
		(17 "Dwgs.User" user "User.Drawings")
		(19 "Cmts.User" user "User.Comments")
		(21 "Eco1.User" user "User.Eco1")
		(23 "Eco2.User" user "User.Eco2")
		(25 "Edge.Cuts" user "Board Geometry/Outline")
		(27 "Margin" user)
		(31 "F.CrtYd" user "Package Geometry/Place Bound Top")
		(29 "B.CrtYd" user "Package Geometry/Place Bound Bottom")
		(35 "F.Fab" user "Ref Des/Assembly Top")
		(33 "B.Fab" user "Ref Des/Assembly Bottom")
	)
	(footprint ""
		(layer "F.Cu")
		(at 35.354514 -76.795122 180)
		(property "Reference" "Q22"
			(at 0 0 180)
			(layer "F.SilkS")
			(hide yes)
			(effects
				(font
					(size 1.27 1.27)
				)
			)
		)
		(property "Value" "PMBS3904-1-GP"
			(at 0 -9.0932 180)
			(unlocked yes)
			(layer "F.Fab")
			(hide yes)
			(effects
				(font
					(size 1.016 1.016)
					(thickness 0.1524)
				)
			)
		)
		(property "Device Type" "SOT-23-10H44"
			(at 0 -10.6172 180)
			(unlocked yes)
			(layer "F.Fab")
			(hide yes)
			(effects
				(font
					(size 1.016 1.016)
					(thickness 0.1524)
				)
			)
		)
		(duplicate_pad_numbers_are_jumpers no)
		(fp_line
			(start 1.651 1.778)
			(end 1.651 -1.778)
			(stroke
				(width 0.1524)
				(type default)
			)
			(layer "F.SilkS")
		)
		(fp_line
			(start 1.651 -1.778)
			(end -1.651 -1.778)
			(stroke
				(width 0.1524)
				(type default)
			)
			(layer "F.SilkS")
		)
		(fp_line
			(start -0.635 1.8796)
			(end -1.7526 1.8796)
			(stroke
				(width 0.3302)
				(type default)
			)
			(layer "F.SilkS")
		)
		(fp_line
			(start -0.71628 2.15265)
			(end -1.26492 2.15265)
			(stroke
				(width 0.0127)
				(type default)
			)
			(layer "F.SilkS")
		)
		(fp_line
			(start -0.719074 2.145538)
			(end -1.265936 2.14122)
			(stroke
				(width 0.0127)
				(type default)
			)
			(layer "F.SilkS")
		)
		(fp_line
			(start -0.9906 1.86309)
			(end -0.701294 2.15265)
			(stroke
				(width 0.0127)
				(type default)
			)
			(layer "F.SilkS")
		)
		(fp_line
			(start -0.994156 1.8669)
			(end -0.987044 1.8669)
			(stroke
				(width 0.0127)
				(type default)
			)
			(layer "F.SilkS")
		)
		(fp_line
			(start -1.003808 1.876552)
			(end -0.977646 1.876552)
			(stroke
				(width 0.0127)
				(type default)
			)
			(layer "F.SilkS")
		)
		(fp_line
			(start -1.013206 1.88595)
			(end -0.967994 1.88595)
			(stroke
				(width 0.0127)
				(type default)
			)
			(layer "F.SilkS")
		)
		(fp_line
			(start -1.022858 1.895602)
			(end -0.958596 1.895602)
			(stroke
				(width 0.0127)
				(type default)
			)
			(layer "F.SilkS")
		)
		(fp_line
			(start -1.032256 1.905)
			(end -0.948944 1.905)
			(stroke
				(width 0.0127)
				(type default)
			)
			(layer "F.SilkS")
		)
		(fp_line
			(start -1.041908 1.914652)
			(end -0.939546 1.914652)
			(stroke
				(width 0.0127)
				(type default)
			)
			(layer "F.SilkS")
		)
		(fp_line
			(start -1.051306 1.92405)
			(end -0.929894 1.92405)
			(stroke
				(width 0.0127)
				(type default)
			)
			(layer "F.SilkS")
		)
		(fp_line
			(start -1.060958 1.933702)
			(end -0.920496 1.933702)
			(stroke
				(width 0.0127)
				(type default)
			)
			(layer "F.SilkS")
		)
		(fp_line
			(start -1.070356 1.9431)
			(end -0.910844 1.9431)
			(stroke
				(width 0.0127)
				(type default)
			)
			(layer "F.SilkS")
		)
		(fp_line
			(start -1.080008 1.952752)
			(end -0.901446 1.952752)
			(stroke
				(width 0.0127)
				(type default)
			)
			(layer "F.SilkS")
		)
		(fp_line
			(start -1.089406 1.96215)
			(end -0.891794 1.96215)
			(stroke
				(width 0.0127)
				(type default)
			)
			(layer "F.SilkS")
		)
		(fp_line
			(start -1.099058 1.971802)
			(end -0.882396 1.971802)
			(stroke
				(width 0.0127)
				(type default)
			)
			(layer "F.SilkS")
		)
		(fp_line
			(start -1.108456 1.9812)
			(end -0.872744 1.9812)
			(stroke
				(width 0.0127)
				(type default)
			)
			(layer "F.SilkS")
		)
		(fp_line
			(start -1.118108 1.990852)
			(end -0.863346 1.990852)
			(stroke
				(width 0.0127)
				(type default)
			)
			(layer "F.SilkS")
		)
		(fp_line
			(start -1.127506 2.00025)
			(end -0.853694 2.00025)
			(stroke
				(width 0.0127)
				(type default)
			)
			(layer "F.SilkS")
		)
		(fp_line
			(start -1.137158 2.009902)
			(end -0.844296 2.009902)
			(stroke
				(width 0.0127)
				(type default)
			)
			(layer "F.SilkS")
		)
		(fp_line
			(start -1.146556 2.0193)
			(end -0.834644 2.0193)
			(stroke
				(width 0.0127)
				(type default)
			)
			(layer "F.SilkS")
		)
		(fp_line
			(start -1.156208 2.028952)
			(end -0.825246 2.028952)
			(stroke
				(width 0.0127)
				(type default)
			)
			(layer "F.SilkS")
		)
		(fp_line
			(start -1.165606 2.03835)
			(end -0.815594 2.03835)
			(stroke
				(width 0.0127)
				(type default)
			)
			(layer "F.SilkS")
		)
		(fp_line
			(start -1.175258 2.048002)
			(end -0.806196 2.048002)
			(stroke
				(width 0.0127)
				(type default)
			)
			(layer "F.SilkS")
		)
		(fp_line
			(start -1.184656 2.0574)
			(end -0.796544 2.0574)
			(stroke
				(width 0.0127)
				(type default)
			)
			(layer "F.SilkS")
		)
		(fp_line
			(start -1.194308 2.067052)
			(end -0.787146 2.067052)
			(stroke
				(width 0.0127)
				(type default)
			)
			(layer "F.SilkS")
		)
		(fp_line
			(start -1.203706 2.07645)
			(end -0.777494 2.07645)
			(stroke
				(width 0.0127)
				(type default)
			)
			(layer "F.SilkS")
		)
		(fp_line
			(start -1.213358 2.086102)
			(end -0.768096 2.086102)
			(stroke
				(width 0.0127)
				(type default)
			)
			(layer "F.SilkS")
		)
		(fp_line
			(start -1.222756 2.0955)
			(end -0.758444 2.0955)
			(stroke
				(width 0.0127)
				(type default)
			)
			(layer "F.SilkS")
		)
		(fp_line
			(start -1.232408 2.105152)
			(end -0.749046 2.105152)
			(stroke
				(width 0.0127)
				(type default)
			)
			(layer "F.SilkS")
		)
		(fp_line
			(start -1.241806 2.11455)
			(end -0.739394 2.11455)
			(stroke
				(width 0.0127)
				(type default)
			)
			(layer "F.SilkS")
		)
		(fp_line
			(start -1.251458 2.124202)
			(end -0.729996 2.124202)
			(stroke
				(width 0.0127)
				(type default)
			)
			(layer "F.SilkS")
		)
		(fp_line
			(start -1.260856 2.1336)
			(end -0.720344 2.1336)
			(stroke
				(width 0.0127)
				(type default)
			)
			(layer "F.SilkS")
		)
		(fp_line
			(start -1.279144 2.15265)
			(end -0.701294 2.15265)
			(stroke
				(width 0.0127)
				(type default)
			)
			(layer "F.SilkS")
		)
		(fp_line
			(start -1.279398 2.152142)
			(end -0.9906 1.86309)
			(stroke
				(width 0.0127)
				(type default)
			)
			(layer "F.SilkS")
		)
		(fp_line
			(start -1.651 1.778)
			(end 1.651 1.778)
			(stroke
				(width 0.1524)
				(type default)
			)
			(layer "F.SilkS")
		)
		(fp_line
			(start -1.651 -1.778)
			(end -1.651 1.778)
			(stroke
				(width 0.1524)
				(type default)
			)
			(layer "F.SilkS")
		)
		(fp_line
			(start -1.7526 1.8796)
			(end -1.7526 0.9906)
			(stroke
				(width 0.3302)
				(type default)
			)
			(layer "F.SilkS")
		)
		(fp_poly
			(pts
				(xy -1.285748 2.159) (xy -1.285748 1.8796) (xy -1.778 1.8796) (xy -1.778 -1.8796) (xy 1.778 -1.8796)
				(xy 1.778 1.8796) (xy -0.694944 1.8796) (xy -0.694944 2.159)
			)
			(stroke
				(width 0)
				(type default)
			)
			(fill no)
			(layer "F.CrtYd")
		)
		(fp_poly
			(pts
				(xy -1.285748 2.159) (xy -1.285748 1.8796) (xy -1.778 1.8796) (xy -1.778 -1.8796) (xy 1.778 -1.8796)
				(xy 1.778 1.8796) (xy -0.694944 1.8796) (xy -0.694944 2.159)
			)
			(stroke
				(width 0)
				(type default)
			)
			(fill no)
			(layer "F.Fab")
		)
		(pad "1" smd rect
			(at -0.98425 0.9525 180)
			(size 0.762 1.143)
			(layers "F.Cu" "F.Mask" "F.Paste")
			(net "INTA_LED_BLUE_B")
		)
		(pad "2" smd rect
			(at 0.98425 0.9525 180)
			(size 0.762 1.143)
			(layers "F.Cu" "F.Mask" "F.Paste")
			(net "GND")
		)
		(pad "3" smd rect
			(at 0 -0.9525 180)
			(size 0.762 1.143)
			(layers "F.Cu" "F.Mask" "F.Paste")
			(net "INTA_LED_BLUE_C")
		)
	)
	(footprint ""
		(layer "F.Cu")
		(at 184.031128 -25.535128 -90)
		(property "Reference" "R455"
			(at 0 0 270)
			(layer "F.SilkS")
			(hide yes)
			(effects
				(font
					(size 1.27 1.27)
				)
			)
		)
		(property "Value" "4K75R2F-1-GP"
			(at 0.064008 -3.993896 270)
			(unlocked yes)
			(layer "F.Fab")
			(hide yes)
			(effects
				(font
					(size 1.016 1.016)
					(thickness 0.1524)
				)
			)
		)
		(property "Device Type" "R402H16"
			(at 0.064008 -5.517896 270)
			(unlocked yes)
			(layer "F.Fab")
			(hide yes)
			(effects
				(font
					(size 1.016 1.016)
					(thickness 0.1524)
				)
			)
		)
		(duplicate_pad_numbers_are_jumpers no)
		(fp_line
			(start -0.508 -0.9398)
			(end -0.508 0.9398)
			(stroke
				(width 0.1524)
				(type default)
			)
			(layer "F.SilkS")
		)
		(fp_line
			(start 0.508 -0.9398)
			(end -0.508 -0.9398)
			(stroke
				(width 0.1524)
				(type default)
			)
			(layer "F.SilkS")
		)
		(fp_rect
			(start -0.508 0.9398)
			(end 0.508 -0.9398)
			(stroke
				(width 0)
				(type default)
			)
			(fill no)
			(layer "F.CrtYd")
		)
		(fp_rect
			(start -0.508 0.9398)
			(end 0.508 -0.9398)
			(stroke
				(width 0)
				(type default)
			)
			(fill no)
			(layer "F.Fab")
		)
		(pad "1" smd custom
			(at 0 -0.4445 270)
			(size 0.1397 0.1397)
			(layers "F.Cu" "F.Mask" "F.Paste")
			(net "P3V3_STBY")
			(options
				(clearance outline)
				(anchor circle)
			)
			(primitives
				(gr_poly
					(pts
						(arc
							(start -0.1778 -0.2794)
							(mid -0.249642 -0.249642)
							(end -0.2794 -0.1778)
						)
						(arc
							(start -0.2794 0.1778)
							(mid -0.249642 0.249642)
							(end -0.1778 0.2794)
						)
						(arc
							(start 0.1778 0.2794)
							(mid 0.249642 0.249642)
							(end 0.2794 0.1778)
						)
						(arc
							(start 0.2794 -0.1778)
							(mid 0.249642 -0.249642)
							(end 0.1778 -0.2794)
						)
					)
					(width 0)
					(fill yes)
				)
			)
		)
		(pad "2" smd custom
			(at 0 0.4445 270)
			(size 0.1397 0.1397)
			(layers "F.Cu" "F.Mask" "F.Paste")
			(net "RMII_BMC_MDC_R")
			(options
				(clearance outline)
				(anchor circle)
			)
			(primitives
				(gr_poly
					(pts
						(arc
							(start -0.1778 -0.2794)
							(mid -0.249642 -0.249642)
							(end -0.2794 -0.1778)
						)
						(arc
							(start -0.2794 0.1778)
							(mid -0.249642 0.249642)
							(end -0.1778 0.2794)
						)
						(arc
							(start 0.1778 0.2794)
							(mid 0.249642 0.249642)
							(end 0.2794 0.1778)
						)
						(arc
							(start 0.2794 -0.1778)
							(mid 0.249642 -0.249642)
							(end 0.1778 -0.2794)
						)
					)
					(width 0)
					(fill yes)
				)
			)
		)
	)
	(footprint ""
		(layer "F.Cu")
		(at 90.17 -236.728)
		(property "Reference" "SU16"
			(at 0 0 0)
			(layer "F.SilkS")
			(hide yes)
			(effects
				(font
					(size 1.27 1.27)
				)
			)
		)
		(property "Value" "PI3C3861-AQE-GP"
			(at 0 -13.1572 0)
			(unlocked yes)
			(layer "F.Fab")
			(hide yes)
			(effects
				(font
					(size 1.016 1.016)
					(thickness 0.1524)
				)
			)
		)
		(property "Device Type" "QSOIC24H69"
			(at 0 -15.1892 0)
			(unlocked yes)
			(layer "F.Fab")
			(hide yes)
			(effects
				(font
					(size 1.016 1.016)
					(thickness 0.1524)
				)
			)
		)
		(duplicate_pad_numbers_are_jumpers no)
		(fp_line
			(start -4.4958 -1.5748)
			(end 3.5814 -1.5748)
			(stroke
				(width 0.1524)
				(type default)
			)
			(layer "F.SilkS")
		)
		(fp_line
			(start -4.4958 -0.4318)
			(end -4.4958 -1.5748)
			(stroke
				(width 0.1524)
				(type default)
			)
			(layer "F.SilkS")
		)
		(fp_line
			(start -4.4958 -0.4318)
			(end -4.064 0)
			(stroke
				(width 0.1524)
				(type default)
			)
			(layer "F.SilkS")
		)
		(fp_line
			(start -4.4958 0.4318)
			(end -4.4958 -0.4318)
			(stroke
				(width 0.1524)
				(type default)
			)
			(layer "F.SilkS")
		)
		(fp_line
			(start -4.4958 0.4318)
			(end -4.4958 1.5748)
			(stroke
				(width 0.1524)
				(type default)
			)
			(layer "F.SilkS")
		)
		(fp_line
			(start -4.318 1.5748)
			(end -4.318 3.556)
			(stroke
				(width 0.508)
				(type default)
			)
			(layer "F.SilkS")
		)
		(fp_line
			(start -4.064 0)
			(end -4.4958 0.4318)
			(stroke
				(width 0.1524)
				(type default)
			)
			(layer "F.SilkS")
		)
		(fp_line
			(start 3.5814 -1.5748)
			(end 3.5814 1.5748)
			(stroke
				(width 0.1524)
				(type default)
			)
			(layer "F.SilkS")
		)
		(fp_line
			(start 3.5814 1.5748)
			(end -4.4958 1.5748)
			(stroke
				(width 0.1524)
				(type default)
			)
			(layer "F.SilkS")
		)
		(fp_line
			(start 3.5814 1.5748)
			(end 3.5814 -1.5748)
			(stroke
				(width 0.1524)
				(type default)
			)
			(layer "F.SilkS")
		)
		(fp_poly
			(pts
				(xy -3.683 -1.5748) (xy 3.5814 -1.5748) (xy 3.5814 1.5748) (xy -3.683 1.5748)
			)
			(stroke
				(width 0)
				(type default)
			)
			(fill yes)
			(layer "F.SilkS")
		)
		(fp_rect
			(start -4.572 3.81)
			(end 4.572 -3.81)
			(stroke
				(width 0)
				(type default)
			)
			(fill no)
			(layer "F.CrtYd")
		)
		(fp_poly
			(pts
				(xy -4.572 -3.81) (xy 4.572 -3.81) (xy 4.572 3.81) (xy -4.572 3.81)
			)
			(stroke
				(width 0)
				(type default)
			)
			(fill no)
			(layer "F.Fab")
		)
		(pad "1" smd rect
			(at -3.4925 2.6162)
			(size 0.3556 1.524)
			(layers "F.Cu" "F.Mask" "F.Paste")
			(net "Net_172")
		)
		(pad "2" smd rect
			(at -2.8575 2.6162)
			(size 0.3556 1.524)
			(layers "F.Cu" "F.Mask" "F.Paste")
			(net "SAS_HDD_LED_10")
		)
		(pad "3" smd rect
			(at -2.2225 2.6162)
			(size 0.3556 1.524)
			(layers "F.Cu" "F.Mask" "F.Paste")
			(net "SAS_HDD_LED_11")
		)
		(pad "4" smd rect
			(at -1.5875 2.6162)
			(size 0.3556 1.524)
			(layers "F.Cu" "F.Mask" "F.Paste")
			(net "SAS_HDD_LED_12")
		)
		(pad "5" smd rect
			(at -0.9525 2.6162)
			(size 0.3556 1.524)
			(layers "F.Cu" "F.Mask" "F.Paste")
			(net "SAS_HDD_LED_13")
		)
		(pad "6" smd rect
			(at -0.3175 2.6162)
			(size 0.3556 1.524)
			(layers "F.Cu" "F.Mask" "F.Paste")
			(net "SAS_HDD_LED_14")
		)
		(pad "7" smd rect
			(at 0.3175 2.6162)
			(size 0.3556 1.524)
			(layers "F.Cu" "F.Mask" "F.Paste")
			(net "SAS_HDD_LED_15")
		)
		(pad "8" smd rect
			(at 0.9525 2.6162)
			(size 0.3556 1.524)
			(layers "F.Cu" "F.Mask" "F.Paste")
			(net "Net_170")
		)
		(pad "9" smd rect
			(at 1.5875 2.6162)
			(size 0.3556 1.524)
			(layers "F.Cu" "F.Mask" "F.Paste")
			(net "Net_171")
		)
		(pad "10" smd rect
			(at 2.2225 2.6162)
			(size 0.3556 1.524)
			(layers "F.Cu" "F.Mask" "F.Paste")
			(net "Net_167")
		)
		(pad "11" smd rect
			(at 2.8575 2.6162)
			(size 0.3556 1.524)
			(layers "F.Cu" "F.Mask" "F.Paste")
			(net "Net_168")
		)
		(pad "12" smd rect
			(at 3.4925 2.6162)
			(size 0.3556 1.524)
			(layers "F.Cu" "F.Mask" "F.Paste")
			(net "GND")
		)
		(pad "13" smd rect
			(at 3.4925 -2.6162)
			(size 0.3556 1.524)
			(layers "F.Cu" "F.Mask" "F.Paste")
			(net "Net_164")
		)
		(pad "14" smd rect
			(at 2.8575 -2.6162)
			(size 0.3556 1.524)
			(layers "F.Cu" "F.Mask" "F.Paste")
			(net "Net_165")
		)
		(pad "15" smd rect
			(at 2.2225 -2.6162)
			(size 0.3556 1.524)
			(layers "F.Cu" "F.Mask" "F.Paste")
			(net "Net_166")
		)
		(pad "16" smd rect
			(at 1.5875 -2.6162)
			(size 0.3556 1.524)
			(layers "F.Cu" "F.Mask" "F.Paste")
			(net "Net_169")
		)
		(pad "17" smd rect
			(at 0.9525 -2.6162)
			(size 0.3556 1.524)
			(layers "F.Cu" "F.Mask" "F.Paste")
			(net "SAS_FAULT_LED15")
		)
		(pad "18" smd rect
			(at 0.3175 -2.6162)
			(size 0.3556 1.524)
			(layers "F.Cu" "F.Mask" "F.Paste")
			(net "SAS_FAULT_LED14")
		)
		(pad "19" smd rect
			(at -0.3175 -2.6162)
			(size 0.3556 1.524)
			(layers "F.Cu" "F.Mask" "F.Paste")
			(net "SAS_FAULT_LED13")
		)
		(pad "20" smd rect
			(at -0.9525 -2.6162)
			(size 0.3556 1.524)
			(layers "F.Cu" "F.Mask" "F.Paste")
			(net "SAS_FAULT_LED12")
		)
		(pad "21" smd rect
			(at -1.5875 -2.6162)
			(size 0.3556 1.524)
			(layers "F.Cu" "F.Mask" "F.Paste")
			(net "SAS_FAULT_LED11")
		)
		(pad "22" smd rect
			(at -2.2225 -2.6162)
			(size 0.3556 1.524)
			(layers "F.Cu" "F.Mask" "F.Paste")
			(net "SAS_FAULT_LED10")
		)
		(pad "23" smd rect
			(at -2.8575 -2.6162)
			(size 0.3556 1.524)
			(layers "F.Cu" "F.Mask" "F.Paste")
			(net "PCIE_MATED#_LED_CD")
		)
		(pad "24" smd rect
			(at -3.4925 -2.6162)
			(size 0.3556 1.524)
			(layers "F.Cu" "F.Mask" "F.Paste")
			(net "P3V3_STBY")
		)
	)
	(footprint ""
		(layer "F.Cu")
		(at 181.356 -221.742 180)
		(property "Reference" "R219"
			(at 0 0 180)
			(layer "F.SilkS")
			(hide yes)
			(effects
				(font
					(size 1.27 1.27)
				)
			)
		)
		(property "Value" "10KR2F-2-GP"
			(at 0.064008 -3.993896 180)
			(unlocked yes)
			(layer "F.Fab")
			(hide yes)
			(effects
				(font
					(size 1.016 1.016)
					(thickness 0.1524)
				)
			)
		)
		(property "Device Type" "R402H16"
			(at 0.064008 -5.517896 180)
			(unlocked yes)
			(layer "F.Fab")
			(hide yes)
			(effects
				(font
					(size 1.016 1.016)
					(thickness 0.1524)
				)
			)
		)
		(duplicate_pad_numbers_are_jumpers no)
		(fp_line
			(start 0.508 -0.9398)
			(end -0.508 -0.9398)
			(stroke
				(width 0.1524)
				(type default)
			)
			(layer "F.SilkS")
		)
		(fp_line
			(start -0.508 -0.9398)
			(end -0.508 0.9398)
			(stroke
				(width 0.1524)
				(type default)
			)
			(layer "F.SilkS")
		)
		(fp_rect
			(start -0.508 0.9398)
			(end 0.508 -0.9398)
			(stroke
				(width 0)
				(type default)
			)
			(fill no)
			(layer "F.CrtYd")
		)
		(fp_rect
			(start -0.508 0.9398)
			(end 0.508 -0.9398)
			(stroke
				(width 0)
				(type default)
			)
			(fill no)
			(layer "F.Fab")
		)
		(pad "1" smd custom
			(at 0 -0.4445 180)
			(size 0.1397 0.1397)
			(layers "F.Cu" "F.Mask" "F.Paste")
			(net "P3V3_STBY")
			(options
				(clearance outline)
				(anchor circle)
			)
			(primitives
				(gr_poly
					(pts
						(arc
							(start -0.1778 -0.2794)
							(mid -0.249642 -0.249642)
							(end -0.2794 -0.1778)
						)
						(arc
							(start -0.2794 0.1778)
							(mid -0.249642 0.249642)
							(end -0.1778 0.2794)
						)
						(arc
							(start 0.1778 0.2794)
							(mid 0.249642 0.249642)
							(end 0.2794 0.1778)
						)
						(arc
							(start 0.2794 -0.1778)
							(mid 0.249642 -0.249642)
							(end 0.1778 -0.2794)
						)
					)
					(width 0)
					(fill yes)
				)
			)
		)
		(pad "2" smd custom
			(at 0 0.4445 180)
			(size 0.1397 0.1397)
			(layers "F.Cu" "F.Mask" "F.Paste")
			(net "PWRBTN_OUT_N")
			(options
				(clearance outline)
				(anchor circle)
			)
			(primitives
				(gr_poly
					(pts
						(arc
							(start -0.1778 -0.2794)
							(mid -0.249642 -0.249642)
							(end -0.2794 -0.1778)
						)
						(arc
							(start -0.2794 0.1778)
							(mid -0.249642 0.249642)
							(end -0.1778 0.2794)
						)
						(arc
							(start 0.1778 0.2794)
							(mid 0.249642 0.249642)
							(end 0.2794 0.1778)
						)
						(arc
							(start 0.2794 -0.1778)
							(mid 0.249642 -0.249642)
							(end 0.1778 -0.2794)
						)
					)
					(width 0)
					(fill yes)
				)
			)
		)
	)
)
